G04 ================== begin FILE IDENTIFICATION RECORD ==================*
G04 Layout Name:  9052_F0T_PDB_Converter_Brick_F_V03_1208_1600.brd*
G04 Film Name:    outline*
G04 File Format:  Gerber RS274X*
G04 File Origin:  Cadence Allegro 17.2-S081*
G04 Origin Date:  Wed Dec 21 09:54:59 2022*
G04 *
G04 Layer:  BOARD GEOMETRY/DESIGN_OUTLINE*
G04 Layer:  BOARD GEOMETRY/CUTOUT*
G04 Layer:  BOARD GEOMETRY/OUTLINE*
G04 *
G04 Offset:    (0.00 0.00)*
G04 Mirror:    No*
G04 Mode:      Positive*
G04 Rotation:  0*
G04 FullContactRelief:  No*
G04 UndefLineWidth:     6.00*
G04 ================== end FILE IDENTIFICATION RECORD ====================*
%FSLAX25Y25*MOIN*%
%IR0*IPPOS*OFA0.00000B0.00000*MIA0B0*SFA1.00000B1.00000*%
%ADD10C,.006*%
G75*
%LPD*%
G75*
G54D10*
G01X0Y518622D02*
G03X11811Y506811I11811J0D01*
G01X37795D01*
G02X39764Y504843I0J-1968D01*
G01Y459567D01*
G02X37795Y457598I-1969J0D01*
G01X11811D01*
G03X0Y445787I0J-11811D01*
G01Y136102D01*
G03X11811Y124291I11811J0D01*
G01X37795D01*
G02X39764Y122323I0J-1969D01*
G01Y77047D01*
G02X37795Y75079I-1969J1D01*
G01X11811D01*
G03X0Y63268I0J-11811D01*
G01Y19685D01*
G03X19685Y0I19685J0D01*
G01X1271654D01*
G03X1291339Y19685I0J19685D01*
G01Y559055D01*
G03X1271654Y578740I-19685J0D01*
G01X19685D01*
G03X0Y559055I0J-19685D01*
G01Y518622D01*
G01X118110Y41339D02*
X106299D01*
X32015Y37415D01*
G02Y57073I-519J9829D01*
G01X106299Y53150D01*
X118110D01*
G02Y41339I0J-5905D01*
G01Y53150D02*
G02Y41339I0J-5905D01*
G01X106299D01*
X32015Y37415D01*
G02Y57073I-519J9829D01*
G01X106299Y53150D01*
X118110D01*
G01X19921Y218504D02*
G02Y209843I0J-4330D01*
G02Y218504I0J4331D01*
G01Y209843D02*
G03Y218504I0J4331D01*
G03Y209843I0J-4330D01*
G01Y372047D02*
G02Y363386I0J-4330D01*
G02Y372047I0J4330D01*
G01Y363386D02*
G03Y372047I0J4330D01*
G03Y363386I0J-4330D01*
G01X32015Y545262D02*
X106299Y541339D01*
X118110D01*
G02Y529528I0J-5906D01*
G01X106299D01*
X32015Y525604D01*
G02Y545262I-519J9829D01*
G01D02*
G03Y525604I-519J-9829D01*
G01X106299Y529528D01*
X118110D01*
G03Y541339I0J5905D01*
G01X106299D01*
X32015Y545262D01*
G01X60630Y107520D02*
G02Y91929I0J-7796D01*
G02Y107520I0J7796D01*
G01Y91929D02*
G02Y107520I0J7796D01*
G02Y91929I0J-7796D01*
G01Y490000D02*
G02Y474409I0J-7796D01*
G02Y490000I0J7796D01*
G01Y474409D02*
G02Y490000I0J7796D01*
G02Y474409I0J-7796D01*
G01X82795Y107520D02*
G02Y91929I0J-7796D01*
G02Y107520I0J7796D01*
G01Y91929D02*
G02Y107520I0J7796D01*
G02Y91929I0J-7796D01*
G01Y490000D02*
G02Y474409I0J-7796D01*
G02Y490000I0J7796D01*
G01Y474409D02*
G02Y490000I0J7796D01*
G02Y474409I0J-7796D01*
G01X108858Y107520D02*
G02Y91929I0J-7796D01*
G02Y107520I0J7796D01*
G01Y91929D02*
G02Y107520I0J7796D01*
G02Y91929I0J-7796D01*
G01Y490000D02*
G02Y474409I0J-7796D01*
G02Y490000I0J7796D01*
G01Y474409D02*
G02Y490000I0J7796D01*
G02Y474409I0J-7796D01*
G01X178819Y281339D02*
G02Y273071I0J-4134D01*
G02Y281339I0J4134D01*
G01Y273071D02*
G03Y281339I0J4134D01*
G03Y273071I0J-4134D01*
G01X193819Y281339D02*
G02Y273071I0J-4134D01*
G02Y281339I0J4134D01*
G01Y273071D02*
G03Y281339I0J4134D01*
G03Y273071I0J-4134D01*
G01Y480354D02*
G02Y474055I0J-3149D01*
G02Y480354I0J3149D01*
G01Y474055D02*
G03Y480354I0J3149D01*
G03Y474055I0J-3149D01*
G01X223819Y480354D02*
G02Y474055I0J-3149D01*
G02Y480354I0J3149D01*
G01Y474055D02*
G03Y480354I0J3149D01*
G03Y474055I0J-3149D01*
G01X268819Y281339D02*
G02Y273071I0J-4134D01*
G02Y281339I0J4134D01*
G01X253819D02*
G02Y273071I0J-4134D01*
G02Y281339I0J4134D01*
G01X268819Y273071D02*
G03Y281339I0J4134D01*
G03Y273071I0J-4134D01*
G01X253819D02*
G03Y281339I0J4134D01*
G03Y273071I0J-4134D01*
G01Y480354D02*
G02Y474055I0J-3149D01*
G02Y480354I0J3149D01*
G01Y474055D02*
G03Y480354I0J3149D01*
G03Y474055I0J-3149D01*
G01X351299Y281339D02*
G02Y273071I0J-4134D01*
G02Y281339I0J4134D01*
G01X336299D02*
G02Y273071I0J-4134D01*
G02Y281339I0J4134D01*
G01X351299Y273071D02*
G03Y281339I0J4134D01*
G03Y273071I0J-4134D01*
G01X336299D02*
G03Y281339I0J4134D01*
G03Y273071I0J-4134D01*
G01X351299Y480354D02*
G02Y474055I0J-3149D01*
G02Y480354I0J3149D01*
G01Y474055D02*
G03Y480354I0J3149D01*
G03Y474055I0J-3149D01*
G01X381299Y480354D02*
G02Y474055I0J-3149D01*
G02Y480354I0J3149D01*
G01Y474055D02*
G03Y480354I0J3149D01*
G03Y474055I0J-3149D01*
G01X425716Y57073D02*
X500000Y53150D01*
X511811D01*
G02Y41339I0J-5905D01*
G01X500000D01*
X425716Y37415D01*
G02Y57073I-519J9829D01*
G01D02*
G03Y37415I-519J-9829D01*
G01X500000Y41339D01*
X511811D01*
G03Y53150I0J5906D01*
G01X500000D01*
X425716Y57073D01*
G01X411299Y281339D02*
G02Y273071I0J-4134D01*
G02Y281339I0J4134D01*
G01Y273071D02*
G03Y281339I0J4134D01*
G03Y273071I0J-4134D01*
G01Y480354D02*
G02Y474055I0J-3149D01*
G02Y480354I0J3149D01*
G01Y474055D02*
G03Y480354I0J3149D01*
G03Y474055I0J-3149D01*
G01X426299Y281339D02*
G02Y273071I0J-4134D01*
G02Y281339I0J4134D01*
G01Y273071D02*
G03Y281339I0J4134D01*
G03Y273071I0J-4134D01*
G01X508780Y281339D02*
G02Y273071I0J-4134D01*
G02Y281339I0J4134D01*
G01X493780D02*
G02Y273071I0J-4134D01*
G02Y281339I0J4134D01*
G01X508780Y273071D02*
G03Y281339I0J4134D01*
G03Y273071I0J-4134D01*
G01X493780D02*
G03Y281339I0J4134D01*
G03Y273071I0J-4134D01*
G01X508780Y480354D02*
G02Y474055I0J-3149D01*
G02Y480354I0J3149D01*
G01Y474055D02*
G03Y480354I0J3149D01*
G03Y474055I0J-3149D01*
G01X538780Y480354D02*
G02Y474055I0J-3149D01*
G02Y480354I0J3149D01*
G01Y474055D02*
G03Y480354I0J3149D01*
G03Y474055I0J-3149D01*
G01X568780Y281339D02*
G02Y273071I0J-4134D01*
G02Y281339I0J4134D01*
G01Y273071D02*
G03Y281339I0J4134D01*
G03Y273071I0J-4134D01*
G01Y480354D02*
G02Y474055I0J-3149D01*
G02Y480354I0J3149D01*
G01Y474055D02*
G03Y480354I0J3149D01*
G03Y474055I0J-3149D01*
G01X583780Y281339D02*
G02Y273071I0J-4134D01*
G02Y281339I0J4134D01*
G01Y273071D02*
G03Y281339I0J4134D01*
G03Y273071I0J-4134D01*
G01X651260Y281339D02*
G02Y273071I0J-4134D01*
G02Y281339I0J4134D01*
G01Y273071D02*
G03Y281339I0J4134D01*
G03Y273071I0J-4134D01*
G01X666260Y281339D02*
G02Y273071I0J-4134D01*
G02Y281339I0J4134D01*
G01Y273071D02*
G03Y281339I0J4134D01*
G03Y273071I0J-4134D01*
G01Y480354D02*
G02Y474055I0J-3149D01*
G02Y480354I0J3149D01*
G01Y474055D02*
G03Y480354I0J3149D01*
G03Y474055I0J-3149D01*
G01X696260Y480354D02*
G02Y474055I0J-3149D01*
G02Y480354I0J3149D01*
G01Y474055D02*
G03Y480354I0J3149D01*
G03Y474055I0J-3149D01*
G01X741260Y281339D02*
G02Y273071I0J-4134D01*
G02Y281339I0J4134D01*
G01X726260D02*
G02Y273071I0J-4134D01*
G02Y281339I0J4134D01*
G01X741260Y273071D02*
G03Y281339I0J4134D01*
G03Y273071I0J-4134D01*
G01X726260D02*
G03Y281339I0J4134D01*
G03Y273071I0J-4134D01*
G01Y480354D02*
G02Y474055I0J-3149D01*
G02Y480354I0J3149D01*
G01Y474055D02*
G03Y480354I0J3149D01*
G03Y474055I0J-3149D01*
G01X905512Y41339D02*
X893701D01*
X819417Y37415D01*
G02Y57073I-519J9829D01*
G01X893701Y53150D01*
X905512D01*
G02Y41339I0J-5905D01*
G01Y53150D02*
G02Y41339I0J-5905D01*
G01X893701D01*
X819417Y37415D01*
G02Y57073I-519J9829D01*
G01X893701Y53150D01*
X905512D01*
G01X902488Y237782D02*
X976772Y233858D01*
X988583D01*
G02Y222047I0J-5905D01*
G01X976772D01*
X902488Y218124D01*
G02Y237782I-519J9829D01*
G01D02*
G03Y218124I-519J-9829D01*
G01X976772Y222047D01*
X988583D01*
G03Y233858I0J5906D01*
G01X976772D01*
X902488Y237782D01*
G01X944417Y552309D02*
X1018701Y548386D01*
X1030512D01*
G02Y536575I0J-5905D01*
G01X1018701D01*
X944417Y532651D01*
G02Y552309I-519J9829D01*
G01D02*
G03Y532651I-519J-9829D01*
G01X1018701Y536575D01*
X1030512D01*
G03Y548386I0J5905D01*
G01X1018701D01*
X944417Y552309D01*
G01X1226024Y182736D02*
G02Y166122I0J-8307D01*
G02Y182736I0J8307D01*
G01Y166122D02*
G03Y182736I0J8307D01*
G03Y166122I0J-8307D01*
G01Y407736D02*
G02Y391122I0J-8307D01*
G02Y407736I0J8307D01*
G01Y391122D02*
G03Y407736I0J8307D01*
G03Y391122I0J-8307D01*
G01X1227559Y57480D02*
G02X1252756I12599J0D01*
G02X1227559I-12598J0D01*
G01X1252756D02*
G03X1227559I-12598J0D01*
G03X1252756I12599J0D01*
G01X1227559Y521260D02*
G02X1252756I12599J0D01*
G02X1227559I-12598J0D01*
G01X1252756D02*
G03X1227559I-12598J0D01*
G03X1252756I12599J0D01*
M02*
